(kicad_pcb
	(version 20260206)
	(generator "pcbnew")
	(generator_version "10.0")
	(general
		(thickness 1.6)
		(legacy_teardrops no)
	)
	(paper "A4")
	(title_block
		(title "01162023_DA0F0TEBIF0_F0T_Expander_BD_F_brd_V02_OCP.brd")
		(comment 1 "Grand Teton / footprints 2067-2072 of 9728")
	)
	(layers
		(0 "F.Cu" signal "TOP")
		(4 "In1.Cu" signal "GND")
		(6 "In2.Cu" signal "VCC")
		(8 "In3.Cu" signal "VCC1")
		(10 "In4.Cu" signal "GND1")
		(12 "In5.Cu" signal "IN1")
		(14 "In6.Cu" signal "GND2")
		(16 "In7.Cu" signal "IN2")
		(18 "In8.Cu" signal "GND3")
		(20 "In9.Cu" signal "IN3")
		(22 "In10.Cu" signal "GND4")
		(24 "In11.Cu" signal "IN4")
		(26 "In12.Cu" signal "GND5")
		(28 "In13.Cu" signal "IN5")
		(30 "In14.Cu" signal "GND6")
		(32 "In15.Cu" signal "IN6")
		(34 "In16.Cu" signal "GND7")
		(2 "B.Cu" signal "BOTTOM")
		(9 "F.Adhes" user "F.Adhesive")
		(11 "B.Adhes" user "B.Adhesive")
		(13 "F.Paste" user "Package Geometry/Pastemask Top")
		(15 "B.Paste" user "Package Geometry/Pastemask Bottom")
		(5 "F.SilkS" user "Ref Des/Silkscreen Top")
		(7 "B.SilkS" user "Ref Des/Silkscreen Bottom")
		(1 "F.Mask" user "Board Geometry/Soldermask Top")
		(3 "B.Mask" user "Board Geometry/Soldermask Bottom")
		(17 "Dwgs.User" user "User.Drawings")
		(19 "Cmts.User" user "User.Comments")
		(21 "Eco1.User" user "User.Eco1")
		(23 "Eco2.User" user "User.Eco2")
		(25 "Edge.Cuts" user "Board Geometry/Outline")
		(27 "Margin" user)
		(31 "F.CrtYd" user "Package Geometry/Place Bound Top")
		(29 "B.CrtYd" user "Package Geometry/Place Bound Bottom")
		(35 "F.Fab" user "Ref Des/Assembly Top")
		(33 "B.Fab" user "Ref Des/Assembly Bottom")
	)
	(footprint ""
		(layer "F.Cu")
		(at 368.00282 -225.49993 180)
		(property "Reference" "U321"
			(at 1.299972 8.679942 0)
			(unlocked yes)
			(layer "F.SilkS")
			(effects
				(font
					(size 0.7874 0.5842)
					(thickness 0.1524)
				)
				(justify left)
			)
		)
		(property "Value" ""
			(at 0 0 180)
			(layer "F.Fab")
			(effects
				(font
					(size 1.27 1.27)
				)
			)
		)
		(duplicate_pad_numbers_are_jumpers no)
		(fp_line
			(start 3.795014 5.2451)
			(end 3.795014 -5.2451)
			(stroke
				(width 0.1524)
				(type default)
			)
			(layer "F.SilkS")
		)
		(fp_line
			(start 3.795014 -5.2451)
			(end 1.9431 -5.2451)
			(stroke
				(width 0.1524)
				(type default)
			)
			(layer "F.SilkS")
		)
		(fp_line
			(start 1.9431 -5.2451)
			(end 0 -3.302)
			(stroke
				(width 0.1524)
				(type default)
			)
			(layer "F.SilkS")
		)
		(fp_line
			(start 0 -3.302)
			(end -1.9431 -5.2451)
			(stroke
				(width 0.1524)
				(type default)
			)
			(layer "F.SilkS")
		)
		(fp_line
			(start -1.9431 -5.2451)
			(end -3.795014 -5.2451)
			(stroke
				(width 0.1524)
				(type default)
			)
			(layer "F.SilkS")
		)
		(fp_line
			(start -3.795014 5.2451)
			(end 3.795014 5.2451)
			(stroke
				(width 0.1524)
				(type default)
			)
			(layer "F.SilkS")
		)
		(fp_line
			(start -3.795014 -5.2451)
			(end -3.795014 5.2451)
			(stroke
				(width 0.1524)
				(type default)
			)
			(layer "F.SilkS")
		)
		(fp_poly
			(pts
				(xy -5.976366 -4.445) (xy -7.239 -3.81381) (xy -7.239 -5.07619)
			)
			(stroke
				(width 0)
				(type default)
			)
			(fill yes)
			(layer "F.SilkS")
		)
		(fp_line
			(start 3.795014 5.2451)
			(end 3.795014 -5.2451)
			(stroke
				(width 0.1)
				(type default)
			)
			(layer "F.Fab")
		)
		(fp_line
			(start 3.795014 -5.2451)
			(end -3.795014 -5.2451)
			(stroke
				(width 0.1)
				(type default)
			)
			(layer "F.Fab")
		)
		(fp_line
			(start -3.795014 5.2451)
			(end 3.795014 5.2451)
			(stroke
				(width 0.1)
				(type default)
			)
			(layer "F.Fab")
		)
		(fp_line
			(start -3.795014 -5.2451)
			(end -3.795014 5.2451)
			(stroke
				(width 0.1)
				(type default)
			)
			(layer "F.Fab")
		)
		(fp_poly
			(pts
				(xy -5.976366 -4.445) (xy -7.239 -3.81381) (xy -7.239 -5.07619)
			)
			(stroke
				(width 0)
				(type default)
			)
			(fill yes)
			(layer "F.Fab")
		)
		(pad "1" smd rect
			(at -4.880102 -4.445 90)
			(size 0.8128 1.905)
			(layers "F.Cu" "F.Mask" "F.Paste")
			(net "SPI_PEX3_SDIO3_R1")
		)
		(pad "2" smd rect
			(at -4.880102 -3.175 90)
			(size 0.8128 1.905)
			(layers "F.Cu" "F.Mask" "F.Paste")
			(net "P1V8_PEX")
		)
		(pad "3" smd rect
			(at -4.880102 -1.905 90)
			(size 0.8128 1.905)
			(layers "F.Cu" "F.Mask" "F.Paste")
			(net "SPI_PEX3_RST_R_N")
		)
		(pad "4" smd rect
			(at -4.880102 -0.635 90)
			(size 0.8128 1.905)
			(layers "F.Cu" "F.Mask" "F.Paste")
			(net "Net_9000")
		)
		(pad "5" smd rect
			(at -4.880102 0.635 90)
			(size 0.8128 1.905)
			(layers "F.Cu" "F.Mask" "F.Paste")
			(net "Net_8999")
		)
		(pad "6" smd rect
			(at -4.880102 1.905 90)
			(size 0.8128 1.905)
			(layers "F.Cu" "F.Mask" "F.Paste")
			(net "Net_8998")
		)
		(pad "7" smd rect
			(at -4.880102 3.175 90)
			(size 0.8128 1.905)
			(layers "F.Cu" "F.Mask" "F.Paste")
			(net "SPI_PEX3_CS_MUX_R_N")
		)
		(pad "8" smd rect
			(at -4.880102 4.445 90)
			(size 0.8128 1.905)
			(layers "F.Cu" "F.Mask" "F.Paste")
			(net "SPI_PEX3_SDIO1_MUX_R")
		)
		(pad "9" smd rect
			(at 4.880102 4.445 270)
			(size 0.8128 1.905)
			(layers "F.Cu" "F.Mask" "F.Paste")
			(net "SPI_PEX3_SDIO2_R1")
		)
		(pad "10" smd rect
			(at 4.880102 3.175 270)
			(size 0.8128 1.905)
			(layers "F.Cu" "F.Mask" "F.Paste")
			(net "GND")
		)
		(pad "11" smd rect
			(at 4.880102 1.905 270)
			(size 0.8128 1.905)
			(layers "F.Cu" "F.Mask" "F.Paste")
			(net "Net_8997")
		)
		(pad "12" smd rect
			(at 4.880102 0.635 270)
			(size 0.8128 1.905)
			(layers "F.Cu" "F.Mask" "F.Paste")
			(net "Net_8996")
		)
		(pad "13" smd rect
			(at 4.880102 -0.635 270)
			(size 0.8128 1.905)
			(layers "F.Cu" "F.Mask" "F.Paste")
			(net "Net_8995")
		)
		(pad "14" smd rect
			(at 4.880102 -1.905 270)
			(size 0.8128 1.905)
			(layers "F.Cu" "F.Mask" "F.Paste")
			(net "Net_8994")
		)
		(pad "15" smd rect
			(at 4.880102 -3.175 270)
			(size 0.8128 1.905)
			(layers "F.Cu" "F.Mask" "F.Paste")
			(net "SPI_PEX3_SDIO0_MUX_R")
		)
		(pad "16" smd rect
			(at 4.880102 -4.445 270)
			(size 0.8128 1.905)
			(layers "F.Cu" "F.Mask" "F.Paste")
			(net "SPI_PEX3_CLK_MUX_R")
		)
	)
	(footprint ""
		(layer "F.Cu")
		(at 268.53515 -79.892906 180)
		(property "Reference" "R1060"
			(at 0 0 180)
			(layer "F.SilkS")
			(hide yes)
			(effects
				(font
					(size 1.27 1.27)
				)
			)
		)
		(property "Value" ""
			(at 0 0 180)
			(layer "F.Fab")
			(effects
				(font
					(size 1.27 1.27)
				)
			)
		)
		(duplicate_pad_numbers_are_jumpers no)
		(fp_line
			(start 0.7874 0.4064)
			(end -0.7874 0.4064)
			(stroke
				(width 0.1524)
				(type default)
			)
			(layer "F.SilkS")
		)
		(fp_line
			(start 0.7874 -0.4064)
			(end 0.7874 0.4064)
			(stroke
				(width 0.1524)
				(type default)
			)
			(layer "F.SilkS")
		)
		(fp_line
			(start -0.7874 0.4064)
			(end -0.7874 -0.4064)
			(stroke
				(width 0.1524)
				(type default)
			)
			(layer "F.SilkS")
		)
		(fp_line
			(start -0.7874 -0.4064)
			(end 0.7874 -0.4064)
			(stroke
				(width 0.1524)
				(type default)
			)
			(layer "F.SilkS")
		)
		(fp_line
			(start 0.67945 0.3048)
			(end 0.120396 0.3048)
			(stroke
				(width 0.1)
				(type default)
			)
			(layer "F.Fab")
		)
		(fp_line
			(start 0.67945 -0.3048)
			(end 0.67945 0.3048)
			(stroke
				(width 0.1)
				(type default)
			)
			(layer "F.Fab")
		)
		(fp_line
			(start 0.12065 -0.2794)
			(end 0.12065 -0.3048)
			(stroke
				(width 0.1)
				(type default)
			)
			(layer "F.Fab")
		)
		(fp_line
			(start 0.12065 -0.3048)
			(end 0.67945 -0.3048)
			(stroke
				(width 0.1)
				(type default)
			)
			(layer "F.Fab")
		)
		(fp_line
			(start 0.120396 0.3048)
			(end 0.120396 0.2794)
			(stroke
				(width 0.1)
				(type default)
			)
			(layer "F.Fab")
		)
		(fp_line
			(start 0.120396 0.2794)
			(end -0.12065 0.2794)
			(stroke
				(width 0.1)
				(type default)
			)
			(layer "F.Fab")
		)
		(fp_line
			(start -0.12065 0.3048)
			(end -0.67945 0.3048)
			(stroke
				(width 0.1)
				(type default)
			)
			(layer "F.Fab")
		)
		(fp_line
			(start -0.12065 0.2794)
			(end -0.12065 0.3048)
			(stroke
				(width 0.1)
				(type default)
			)
			(layer "F.Fab")
		)
		(fp_line
			(start -0.12065 -0.2794)
			(end 0.12065 -0.2794)
			(stroke
				(width 0.1)
				(type default)
			)
			(layer "F.Fab")
		)
		(fp_line
			(start -0.12065 -0.305054)
			(end -0.12065 -0.2794)
			(stroke
				(width 0.1)
				(type default)
			)
			(layer "F.Fab")
		)
		(fp_line
			(start -0.67945 0.3048)
			(end -0.67945 -0.305054)
			(stroke
				(width 0.1)
				(type default)
			)
			(layer "F.Fab")
		)
		(fp_line
			(start -0.67945 -0.305054)
			(end -0.12065 -0.305054)
			(stroke
				(width 0.1)
				(type default)
			)
			(layer "F.Fab")
		)
		(pad "1" smd circle
			(at -0.40005 0 180)
			(size 0 0)
			(layers "F.Cu" "F.Mask" "F.Paste")
			(net "GND")
		)
		(pad "2" smd circle
			(at 0.40005 0 180)
			(size 0 0)
			(layers "F.Cu" "F.Mask" "F.Paste")
			(net "CLK_BUFFER_9ZXL0851E_0_7_OE1_N")
		)
	)
	(footprint ""
		(layer "F.Cu")
		(at 150.855934 -115.590574 90)
		(property "Reference" "U19"
			(at 2.518156 -0.183134 0)
			(unlocked yes)
			(layer "F.SilkS")
			(effects
				(font
					(size 0.7874 0.5842)
					(thickness 0.1524)
				)
			)
		)
		(property "Value" ""
			(at 0 0 90)
			(layer "F.Fab")
			(effects
				(font
					(size 1.27 1.27)
				)
			)
		)
		(duplicate_pad_numbers_are_jumpers no)
		(fp_line
			(start -1.949958 -1.610106)
			(end 1.949958 -1.610106)
			(stroke
				(width 0.1524)
				(type default)
			)
			(layer "F.SilkS")
		)
		(fp_line
			(start 1.949958 -1.560068)
			(end 1.949958 1.610106)
			(stroke
				(width 0.1524)
				(type default)
			)
			(layer "F.SilkS")
		)
		(fp_line
			(start 1.949958 1.610106)
			(end -1.949958 1.610106)
			(stroke
				(width 0.1524)
				(type default)
			)
			(layer "F.SilkS")
		)
		(fp_line
			(start -1.949958 1.610106)
			(end -1.949958 -1.610106)
			(stroke
				(width 0.1524)
				(type default)
			)
			(layer "F.SilkS")
		)
		(fp_line
			(start 0.750062 -1.560068)
			(end 0.750062 1.560068)
			(stroke
				(width 0.1)
				(type default)
			)
			(layer "F.Fab")
		)
		(fp_line
			(start -0.750062 -1.560068)
			(end 0.750062 -1.560068)
			(stroke
				(width 0.1)
				(type default)
			)
			(layer "F.Fab")
		)
		(fp_line
			(start 0.750062 1.560068)
			(end -0.750062 1.560068)
			(stroke
				(width 0.1)
				(type default)
			)
			(layer "F.Fab")
		)
		(fp_line
			(start -0.750062 1.560068)
			(end -0.750062 -1.560068)
			(stroke
				(width 0.1)
				(type default)
			)
			(layer "F.Fab")
		)
		(pad "D" smd rect
			(at 1.100074 0)
			(size 1.016 1.4224)
			(layers "F.Cu" "F.Mask" "F.Paste")
			(net "HP_NIC2_EN")
		)
		(pad "G" smd rect
			(at -1.100074 -0.94996)
			(size 1.016 1.4224)
			(layers "F.Cu" "F.Mask" "F.Paste")
			(net "PRSNT_NIC2_R_N")
		)
		(pad "S" smd rect
			(at -1.100074 0.94996)
			(size 1.016 1.4224)
			(layers "F.Cu" "F.Mask" "F.Paste")
			(net "GND")
		)
	)
	(footprint ""
		(layer "F.Cu")
		(at 281.04592 -46.4439 180)
		(property "Reference" "U72"
			(at 0.52832 -2.40157 0)
			(unlocked yes)
			(layer "F.SilkS")
			(effects
				(font
					(size 0.7874 0.5842)
					(thickness 0.1524)
				)
			)
		)
		(property "Value" ""
			(at 0 0 180)
			(layer "F.Fab")
			(effects
				(font
					(size 1.27 1.27)
				)
			)
		)
		(duplicate_pad_numbers_are_jumpers no)
		(fp_line
			(start 1.500124 1.500124)
			(end 1.004062 1.500124)
			(stroke
				(width 0.1524)
				(type default)
			)
			(layer "F.SilkS")
		)
		(fp_line
			(start 1.500124 1.004062)
			(end 1.500124 1.500124)
			(stroke
				(width 0.1524)
				(type default)
			)
			(layer "F.SilkS")
		)
		(fp_line
			(start 1.500124 -1.500124)
			(end 1.500124 -1.004062)
			(stroke
				(width 0.1524)
				(type default)
			)
			(layer "F.SilkS")
		)
		(fp_line
			(start 1.004062 -1.500124)
			(end 1.500124 -1.500124)
			(stroke
				(width 0.1524)
				(type default)
			)
			(layer "F.SilkS")
		)
		(fp_line
			(start -1.004062 1.500124)
			(end -1.500124 1.500124)
			(stroke
				(width 0.1524)
				(type default)
			)
			(layer "F.SilkS")
		)
		(fp_line
			(start -1.500124 1.500124)
			(end -1.500124 1.004062)
			(stroke
				(width 0.1524)
				(type default)
			)
			(layer "F.SilkS")
		)
		(fp_line
			(start -1.500124 -1.004062)
			(end -1.500124 -1.500124)
			(stroke
				(width 0.1524)
				(type default)
			)
			(layer "F.SilkS")
		)
		(fp_line
			(start -1.500124 -1.500124)
			(end -1.004062 -1.500124)
			(stroke
				(width 0.1524)
				(type default)
			)
			(layer "F.SilkS")
		)
		(fp_poly
			(pts
				(xy -1.6764 -2.789428) (xy -2.394966 -2.071116) (xy -1.317244 -1.71196)
			)
			(stroke
				(width 0)
				(type default)
			)
			(fill yes)
			(layer "F.SilkS")
		)
		(fp_line
			(start 1.500124 1.500124)
			(end -1.500124 1.500124)
			(stroke
				(width 0.1)
				(type default)
			)
			(layer "F.Fab")
		)
		(fp_line
			(start 1.500124 -1.500124)
			(end 1.500124 1.500124)
			(stroke
				(width 0.1)
				(type default)
			)
			(layer "F.Fab")
		)
		(fp_line
			(start -1.500124 1.500124)
			(end -1.500124 -1.500124)
			(stroke
				(width 0.1)
				(type default)
			)
			(layer "F.Fab")
		)
		(fp_line
			(start -1.500124 -1.500124)
			(end 1.500124 -1.500124)
			(stroke
				(width 0.1)
				(type default)
			)
			(layer "F.Fab")
		)
		(fp_poly
			(pts
				(xy -2.847848 -1.258062) (xy -2.847848 -0.242062) (xy -1.831848 -0.750062)
			)
			(stroke
				(width 0)
				(type default)
			)
			(fill yes)
			(layer "F.Fab")
		)
		(pad "1" smd rect
			(at -1.400048 -0.750062 90)
			(size 0.2286 0.6096)
			(layers "F.Cu" "F.Mask" "F.Paste")
			(net "SSD9_ADC_A1")
		)
		(pad "2" smd rect
			(at -1.400048 -0.249936 90)
			(size 0.2286 0.6096)
			(layers "F.Cu" "F.Mask" "F.Paste")
			(net "SSD9_ADC_A0")
		)
		(pad "3" smd rect
			(at -1.400048 0.249936 90)
			(size 0.2286 0.6096)
			(layers "F.Cu" "F.Mask" "F.Paste")
			(net "SSD9_ADC_ALERT_N")
		)
		(pad "4" smd rect
			(at -1.400048 0.750062 90)
			(size 0.2286 0.6096)
			(layers "F.Cu" "F.Mask" "F.Paste")
			(net "SMB_SSD9_ADC_SDA")
		)
		(pad "5" smd rect
			(at -0.750062 1.400048 180)
			(size 0.2286 0.6096)
			(layers "F.Cu" "F.Mask" "F.Paste")
			(net "SMB_SSD9_ADC_SCL")
		)
		(pad "6" smd rect
			(at -0.249936 1.400048 180)
			(size 0.2286 0.6096)
			(layers "F.Cu" "F.Mask" "F.Paste")
			(net "Net_8708")
		)
		(pad "7" smd rect
			(at 0.249936 1.400048 180)
			(size 0.2286 0.6096)
			(layers "F.Cu" "F.Mask" "F.Paste")
			(net "Net_8707")
		)
		(pad "8" smd rect
			(at 0.750062 1.400048 180)
			(size 0.2286 0.6096)
			(layers "F.Cu" "F.Mask" "F.Paste")
			(net "Net_8706")
		)
		(pad "9" smd rect
			(at 1.400048 0.750062 90)
			(size 0.2286 0.6096)
			(layers "F.Cu" "F.Mask" "F.Paste")
			(net "P3V3_AUX")
		)
		(pad "10" smd rect
			(at 1.400048 0.249936 90)
			(size 0.2286 0.6096)
			(layers "F.Cu" "F.Mask" "F.Paste")
			(net "GND")
		)
		(pad "11" smd rect
			(at 1.400048 -0.249936 90)
			(size 0.2286 0.6096)
			(layers "F.Cu" "F.Mask" "F.Paste")
			(net "P12V_SSD9_R")
		)
		(pad "12" smd rect
			(at 1.400048 -0.750062 90)
			(size 0.2286 0.6096)
			(layers "F.Cu" "F.Mask" "F.Paste")
			(net "P12V_SSD9_VIN_N")
		)
		(pad "13" smd rect
			(at 0.750062 -1.400048 180)
			(size 0.2286 0.6096)
			(layers "F.Cu" "F.Mask" "F.Paste")
			(net "P12V_SSD9_VIN_P")
		)
		(pad "14" smd rect
			(at 0.249936 -1.400048 180)
			(size 0.2286 0.6096)
			(layers "F.Cu" "F.Mask" "F.Paste")
			(net "Net_8705")
		)
		(pad "15" smd rect
			(at -0.249936 -1.400048 180)
			(size 0.2286 0.6096)
			(layers "F.Cu" "F.Mask" "F.Paste")
			(net "Net_8704")
		)
		(pad "16" smd rect
			(at -0.750062 -1.400048 180)
			(size 0.2286 0.6096)
			(layers "F.Cu" "F.Mask" "F.Paste")
			(net "Net_8703")
		)
		(pad "TH" smd rect
			(at 0 0 180)
			(size 1.7018 1.7018)
			(layers "F.Cu" "F.Mask" "F.Paste")
			(net "GND")
		)
		(zone
			(layer "F.Cu")
			(hatch none 0.5)
			(connect_pads
				(clearance 0)
			)
			(min_thickness 0.25)
			(keepout
				(tracks not_allowed)
				(vias allowed)
				(pads allowed)
				(copperpour not_allowed)
				(footprints allowed)
			)
			(placement
				(enabled no)
				(sheetname "")
			)
			(fill
				(thermal_gap 0.5)
				(thermal_bridge_width 0.5)
				(island_removal_mode 0)
			)
			(polygon
				(pts
					(xy 282.090368 -46.4185) (xy 282.090368 -45.399452) (xy 280.001472 -45.399452) (xy 280.001472 -47.488348)
					(xy 282.090368 -47.488348) (xy 282.090368 -46.4439) (xy 281.94762 -46.4439) (xy 281.94762 -47.3456)
					(xy 280.14422 -47.3456) (xy 280.14422 -45.5422) (xy 281.94762 -45.5422) (xy 281.94762 -46.4185)
				)
			)
		)
	)
	(footprint ""
		(layer "F.Cu")
		(at 374.27154 -350.098614 90)
		(property "Reference" "C764"
			(at 0 0 90)
			(layer "F.SilkS")
			(hide yes)
			(effects
				(font
					(size 1.27 1.27)
				)
			)
		)
		(property "Value" ""
			(at 0 0 90)
			(layer "F.Fab")
			(effects
				(font
					(size 1.27 1.27)
				)
			)
		)
		(duplicate_pad_numbers_are_jumpers no)
		(fp_line
			(start 0.299974 -0.150114)
			(end 0.299974 0.150114)
			(stroke
				(width 0.1)
				(type default)
			)
			(layer "F.Fab")
		)
		(fp_line
			(start -0.299974 -0.150114)
			(end 0.299974 -0.150114)
			(stroke
				(width 0.1)
				(type default)
			)
			(layer "F.Fab")
		)
		(fp_line
			(start 0.299974 0.150114)
			(end -0.299974 0.150114)
			(stroke
				(width 0.1)
				(type default)
			)
			(layer "F.Fab")
		)
		(fp_line
			(start -0.299974 0.150114)
			(end -0.299974 -0.150114)
			(stroke
				(width 0.1)
				(type default)
			)
			(layer "F.Fab")
		)
		(pad "1" smd rect
			(at -0.2667 0 90)
			(size 0.3048 0.381)
			(layers "F.Cu" "F.Mask" "F.Paste")
			(net "P5E_PEX3_STN6_TX_DP<110>")
		)
		(pad "2" smd rect
			(at 0.2667 0 90)
			(size 0.3048 0.381)
			(layers "F.Cu" "F.Mask" "F.Paste")
			(net "P5E_PEX3_STN6_TX_C_DP<110>")
		)
	)
	(footprint ""
		(layer "F.Cu")
		(at 130.490468 -343.952322 90)
		(property "Reference" "C2257"
			(at 0 0 90)
			(layer "F.SilkS")
			(hide yes)
			(effects
				(font
					(size 1.27 1.27)
				)
			)
		)
		(property "Value" ""
			(at 0 0 90)
			(layer "F.Fab")
			(effects
				(font
					(size 1.27 1.27)
				)
			)
		)
		(duplicate_pad_numbers_are_jumpers no)
		(fp_line
			(start 0.299974 -0.150114)
			(end 0.299974 0.150114)
			(stroke
				(width 0.1)
				(type default)
			)
			(layer "F.Fab")
		)
		(fp_line
			(start -0.299974 -0.150114)
			(end 0.299974 -0.150114)
			(stroke
				(width 0.1)
				(type default)
			)
			(layer "F.Fab")
		)
		(fp_line
			(start 0.299974 0.150114)
			(end -0.299974 0.150114)
			(stroke
				(width 0.1)
				(type default)
			)
			(layer "F.Fab")
		)
		(fp_line
			(start -0.299974 0.150114)
			(end -0.299974 -0.150114)
			(stroke
				(width 0.1)
				(type default)
			)
			(layer "F.Fab")
		)
		(pad "1" smd rect
			(at -0.2667 0 90)
			(size 0.3048 0.381)
			(layers "F.Cu" "F.Mask" "F.Paste")
			(net "P5E_PEX1_STN5_TX_DP<88>")
		)
		(pad "2" smd rect
			(at 0.2667 0 90)
			(size 0.3048 0.381)
			(layers "F.Cu" "F.Mask" "F.Paste")
			(net "P5E_PEX1_STN5_TX_C_DP<88>")
		)
	)
)
